(kicad_pcb
	(version 20260206)
	(generator "pcbnew")
	(generator_version "10.0")
	(general
		(thickness 1.6)
		(legacy_teardrops no)
	)
	(paper "A4")
	(title_block
		(title "03242023_DA0F0TMBIJ0_F0T_Motherboard_J_brd_V01_OCP.brd")
		(comment 1 "Grand Teton / footprints 3147-3154 of 6105")
	)
	(layers
		(0 "F.Cu" signal "TOP")
		(4 "In1.Cu" signal "GND")
		(6 "In2.Cu" signal "IN1")
		(8 "In3.Cu" signal "GND1")
		(10 "In4.Cu" signal "IN2")
		(12 "In5.Cu" signal "GND2")
		(14 "In6.Cu" signal "IN3")
		(16 "In7.Cu" signal "GND3")
		(18 "In8.Cu" signal "VCC")
		(20 "In9.Cu" signal "VCC1")
		(22 "In10.Cu" signal "GND4")
		(24 "In11.Cu" signal "IN4")
		(26 "In12.Cu" signal "GND5")
		(28 "In13.Cu" signal "IN5")
		(30 "In14.Cu" signal "GND6")
		(32 "In15.Cu" signal "IN6")
		(34 "In16.Cu" signal "GND7")
		(2 "B.Cu" signal "BOTTOM")
		(9 "F.Adhes" user "F.Adhesive")
		(11 "B.Adhes" user "B.Adhesive")
		(13 "F.Paste" user "Package Geometry/Pastemask Top")
		(15 "B.Paste" user "Package Geometry/Pastemask Bottom")
		(5 "F.SilkS" user "Ref Des/Silkscreen Top")
		(7 "B.SilkS" user "Ref Des/Silkscreen Bottom")
		(1 "F.Mask" user "Board Geometry/Soldermask Top")
		(3 "B.Mask" user "Board Geometry/Soldermask Bottom")
		(17 "Dwgs.User" user "User.Drawings")
		(19 "Cmts.User" user "User.Comments")
		(21 "Eco1.User" user "User.Eco1")
		(23 "Eco2.User" user "User.Eco2")
		(25 "Edge.Cuts" user "Board Geometry/Outline")
		(27 "Margin" user)
		(31 "F.CrtYd" user "Package Geometry/Place Bound Top")
		(29 "B.CrtYd" user "Package Geometry/Place Bound Bottom")
		(35 "F.Fab" user "Ref Des/Assembly Top")
		(33 "B.Fab" user "Ref Des/Assembly Bottom")
	)
	(footprint ""
		(layer "F.Cu")
		(at 434.080158 -118.568216 90)
		(property "Reference" "R2403"
			(at 0 0 90)
			(layer "F.SilkS")
			(hide yes)
			(effects
				(font
					(size 1.27 1.27)
				)
			)
		)
		(property "Value" ""
			(at 0 0 90)
			(layer "F.Fab")
			(effects
				(font
					(size 1.27 1.27)
				)
			)
		)
		(duplicate_pad_numbers_are_jumpers no)
		(fp_line
			(start 0.7874 -0.4064)
			(end 0.7874 0.4064)
			(stroke
				(width 0.1524)
				(type default)
			)
			(layer "F.SilkS")
		)
		(fp_line
			(start -0.7874 -0.4064)
			(end 0.7874 -0.4064)
			(stroke
				(width 0.1524)
				(type default)
			)
			(layer "F.SilkS")
		)
		(fp_line
			(start 0.7874 0.4064)
			(end -0.7874 0.4064)
			(stroke
				(width 0.1524)
				(type default)
			)
			(layer "F.SilkS")
		)
		(fp_line
			(start -0.7874 0.4064)
			(end -0.7874 -0.4064)
			(stroke
				(width 0.1524)
				(type default)
			)
			(layer "F.SilkS")
		)
		(fp_line
			(start -0.12065 -0.305054)
			(end -0.12065 -0.2794)
			(stroke
				(width 0.1)
				(type default)
			)
			(layer "F.Fab")
		)
		(fp_line
			(start -0.67945 -0.305054)
			(end -0.12065 -0.305054)
			(stroke
				(width 0.1)
				(type default)
			)
			(layer "F.Fab")
		)
		(fp_line
			(start 0.67945 -0.3048)
			(end 0.67945 0.3048)
			(stroke
				(width 0.1)
				(type default)
			)
			(layer "F.Fab")
		)
		(fp_line
			(start 0.12065 -0.3048)
			(end 0.67945 -0.3048)
			(stroke
				(width 0.1)
				(type default)
			)
			(layer "F.Fab")
		)
		(fp_line
			(start 0.12065 -0.2794)
			(end 0.12065 -0.3048)
			(stroke
				(width 0.1)
				(type default)
			)
			(layer "F.Fab")
		)
		(fp_line
			(start -0.12065 -0.2794)
			(end 0.12065 -0.2794)
			(stroke
				(width 0.1)
				(type default)
			)
			(layer "F.Fab")
		)
		(fp_line
			(start 0.120396 0.2794)
			(end -0.12065 0.2794)
			(stroke
				(width 0.1)
				(type default)
			)
			(layer "F.Fab")
		)
		(fp_line
			(start -0.12065 0.2794)
			(end -0.12065 0.3048)
			(stroke
				(width 0.1)
				(type default)
			)
			(layer "F.Fab")
		)
		(fp_line
			(start 0.67945 0.3048)
			(end 0.120396 0.3048)
			(stroke
				(width 0.1)
				(type default)
			)
			(layer "F.Fab")
		)
		(fp_line
			(start 0.120396 0.3048)
			(end 0.120396 0.2794)
			(stroke
				(width 0.1)
				(type default)
			)
			(layer "F.Fab")
		)
		(fp_line
			(start -0.12065 0.3048)
			(end -0.67945 0.3048)
			(stroke
				(width 0.1)
				(type default)
			)
			(layer "F.Fab")
		)
		(fp_line
			(start -0.67945 0.3048)
			(end -0.67945 -0.305054)
			(stroke
				(width 0.1)
				(type default)
			)
			(layer "F.Fab")
		)
		(pad "1" smd circle
			(at -0.40005 0 90)
			(size 0 0)
			(layers "F.Cu" "F.Mask" "F.Paste")
			(net "SMB_VR_3V3AUX_SDA_R2")
		)
		(pad "2" smd circle
			(at 0.40005 0 90)
			(size 0 0)
			(layers "F.Cu" "F.Mask" "F.Paste")
			(net "SMB_DIO_PVCCD_HV_CPU0")
		)
	)
	(footprint ""
		(layer "F.Cu")
		(at 379.78461 -408.517344 -90)
		(property "Reference" "C875"
			(at 0 0 270)
			(layer "F.SilkS")
			(hide yes)
			(effects
				(font
					(size 1.27 1.27)
				)
			)
		)
		(property "Value" ""
			(at 0 0 270)
			(layer "F.Fab")
			(effects
				(font
					(size 1.27 1.27)
				)
			)
		)
		(duplicate_pad_numbers_are_jumpers no)
		(fp_line
			(start -0.299974 0.150114)
			(end -0.299974 -0.150114)
			(stroke
				(width 0.1)
				(type default)
			)
			(layer "F.Fab")
		)
		(fp_line
			(start 0.299974 0.150114)
			(end -0.299974 0.150114)
			(stroke
				(width 0.1)
				(type default)
			)
			(layer "F.Fab")
		)
		(fp_line
			(start -0.299974 -0.150114)
			(end 0.299974 -0.150114)
			(stroke
				(width 0.1)
				(type default)
			)
			(layer "F.Fab")
		)
		(fp_line
			(start 0.299974 -0.150114)
			(end 0.299974 0.150114)
			(stroke
				(width 0.1)
				(type default)
			)
			(layer "F.Fab")
		)
		(pad "1" smd rect
			(at -0.2667 0 270)
			(size 0.3048 0.381)
			(layers "F.Cu" "F.Mask" "F.Paste")
			(net "P5E_CPU0_PE3_TX_C_DP<13>")
		)
		(pad "2" smd rect
			(at 0.2667 0 270)
			(size 0.3048 0.381)
			(layers "F.Cu" "F.Mask" "F.Paste")
			(net "P5E_CPU0_PE3_TX_DP<13>")
		)
	)
	(footprint ""
		(layer "F.Cu")
		(at 167.424354 -408.517344 -90)
		(property "Reference" "C1547"
			(at 0 0 270)
			(layer "F.SilkS")
			(hide yes)
			(effects
				(font
					(size 1.27 1.27)
				)
			)
		)
		(property "Value" ""
			(at 0 0 270)
			(layer "F.Fab")
			(effects
				(font
					(size 1.27 1.27)
				)
			)
		)
		(duplicate_pad_numbers_are_jumpers no)
		(fp_line
			(start -0.299974 0.150114)
			(end -0.299974 -0.150114)
			(stroke
				(width 0.1)
				(type default)
			)
			(layer "F.Fab")
		)
		(fp_line
			(start 0.299974 0.150114)
			(end -0.299974 0.150114)
			(stroke
				(width 0.1)
				(type default)
			)
			(layer "F.Fab")
		)
		(fp_line
			(start -0.299974 -0.150114)
			(end 0.299974 -0.150114)
			(stroke
				(width 0.1)
				(type default)
			)
			(layer "F.Fab")
		)
		(fp_line
			(start 0.299974 -0.150114)
			(end 0.299974 0.150114)
			(stroke
				(width 0.1)
				(type default)
			)
			(layer "F.Fab")
		)
		(pad "1" smd rect
			(at -0.2667 0 270)
			(size 0.3048 0.381)
			(layers "F.Cu" "F.Mask" "F.Paste")
			(net "P5E_CPU1_PE3_TX_C_DP<0>")
		)
		(pad "2" smd rect
			(at 0.2667 0 270)
			(size 0.3048 0.381)
			(layers "F.Cu" "F.Mask" "F.Paste")
			(net "P5E_CPU1_PE3_TX_DP<0>")
		)
	)
	(footprint ""
		(layer "F.Cu")
		(at 164.64788 -120.106948 180)
		(property "Reference" "R3176"
			(at 0 0 180)
			(layer "F.SilkS")
			(hide yes)
			(effects
				(font
					(size 1.27 1.27)
				)
			)
		)
		(property "Value" ""
			(at 0 0 180)
			(layer "F.Fab")
			(effects
				(font
					(size 1.27 1.27)
				)
			)
		)
		(duplicate_pad_numbers_are_jumpers no)
		(fp_line
			(start 0.7874 0.4064)
			(end -0.7874 0.4064)
			(stroke
				(width 0.1524)
				(type default)
			)
			(layer "F.SilkS")
		)
		(fp_line
			(start 0.7874 -0.4064)
			(end 0.7874 0.4064)
			(stroke
				(width 0.1524)
				(type default)
			)
			(layer "F.SilkS")
		)
		(fp_line
			(start -0.7874 0.4064)
			(end -0.7874 -0.4064)
			(stroke
				(width 0.1524)
				(type default)
			)
			(layer "F.SilkS")
		)
		(fp_line
			(start -0.7874 -0.4064)
			(end 0.7874 -0.4064)
			(stroke
				(width 0.1524)
				(type default)
			)
			(layer "F.SilkS")
		)
		(fp_line
			(start 0.67945 0.3048)
			(end 0.120396 0.3048)
			(stroke
				(width 0.1)
				(type default)
			)
			(layer "F.Fab")
		)
		(fp_line
			(start 0.67945 -0.3048)
			(end 0.67945 0.3048)
			(stroke
				(width 0.1)
				(type default)
			)
			(layer "F.Fab")
		)
		(fp_line
			(start 0.12065 -0.2794)
			(end 0.12065 -0.3048)
			(stroke
				(width 0.1)
				(type default)
			)
			(layer "F.Fab")
		)
		(fp_line
			(start 0.12065 -0.3048)
			(end 0.67945 -0.3048)
			(stroke
				(width 0.1)
				(type default)
			)
			(layer "F.Fab")
		)
		(fp_line
			(start 0.120396 0.3048)
			(end 0.120396 0.2794)
			(stroke
				(width 0.1)
				(type default)
			)
			(layer "F.Fab")
		)
		(fp_line
			(start 0.120396 0.2794)
			(end -0.12065 0.2794)
			(stroke
				(width 0.1)
				(type default)
			)
			(layer "F.Fab")
		)
		(fp_line
			(start -0.12065 0.3048)
			(end -0.67945 0.3048)
			(stroke
				(width 0.1)
				(type default)
			)
			(layer "F.Fab")
		)
		(fp_line
			(start -0.12065 0.2794)
			(end -0.12065 0.3048)
			(stroke
				(width 0.1)
				(type default)
			)
			(layer "F.Fab")
		)
		(fp_line
			(start -0.12065 -0.2794)
			(end 0.12065 -0.2794)
			(stroke
				(width 0.1)
				(type default)
			)
			(layer "F.Fab")
		)
		(fp_line
			(start -0.12065 -0.305054)
			(end -0.12065 -0.2794)
			(stroke
				(width 0.1)
				(type default)
			)
			(layer "F.Fab")
		)
		(fp_line
			(start -0.67945 0.3048)
			(end -0.67945 -0.305054)
			(stroke
				(width 0.1)
				(type default)
			)
			(layer "F.Fab")
		)
		(fp_line
			(start -0.67945 -0.305054)
			(end -0.12065 -0.305054)
			(stroke
				(width 0.1)
				(type default)
			)
			(layer "F.Fab")
		)
		(pad "1" smd circle
			(at -0.40005 0 180)
			(size 0 0)
			(layers "F.Cu" "F.Mask" "F.Paste")
			(net "SGPIO_OCP_V3_2_CLK")
		)
		(pad "2" smd circle
			(at 0.40005 0 180)
			(size 0 0)
			(layers "F.Cu" "F.Mask" "F.Paste")
			(net "P3V3_OCP_V3_2")
		)
	)
	(footprint ""
		(layer "F.Cu")
		(at 362.646468 -360.83875)
		(property "Reference" "PC330"
			(at 0 0 0)
			(layer "F.SilkS")
			(hide yes)
			(effects
				(font
					(size 1.27 1.27)
				)
			)
		)
		(property "Value" ""
			(at 0 0 0)
			(layer "F.Fab")
			(effects
				(font
					(size 1.27 1.27)
				)
			)
		)
		(duplicate_pad_numbers_are_jumpers no)
		(fp_line
			(start -0.7874 -0.4064)
			(end 0.7874 -0.4064)
			(stroke
				(width 0.1524)
				(type default)
			)
			(layer "F.SilkS")
		)
		(fp_line
			(start -0.7874 0.4064)
			(end -0.7874 -0.4064)
			(stroke
				(width 0.1524)
				(type default)
			)
			(layer "F.SilkS")
		)
		(fp_line
			(start 0.7874 -0.4064)
			(end 0.7874 0.4064)
			(stroke
				(width 0.1524)
				(type default)
			)
			(layer "F.SilkS")
		)
		(fp_line
			(start 0.7874 0.4064)
			(end -0.7874 0.4064)
			(stroke
				(width 0.1524)
				(type default)
			)
			(layer "F.SilkS")
		)
		(fp_line
			(start -0.67945 -0.305054)
			(end -0.12065 -0.305054)
			(stroke
				(width 0.1)
				(type default)
			)
			(layer "F.Fab")
		)
		(fp_line
			(start -0.67945 0.3048)
			(end -0.67945 -0.305054)
			(stroke
				(width 0.1)
				(type default)
			)
			(layer "F.Fab")
		)
		(fp_line
			(start -0.12065 -0.305054)
			(end -0.12065 -0.2794)
			(stroke
				(width 0.1)
				(type default)
			)
			(layer "F.Fab")
		)
		(fp_line
			(start -0.12065 -0.2794)
			(end 0.12065 -0.2794)
			(stroke
				(width 0.1)
				(type default)
			)
			(layer "F.Fab")
		)
		(fp_line
			(start -0.12065 0.2794)
			(end -0.12065 0.3048)
			(stroke
				(width 0.1)
				(type default)
			)
			(layer "F.Fab")
		)
		(fp_line
			(start -0.12065 0.3048)
			(end -0.67945 0.3048)
			(stroke
				(width 0.1)
				(type default)
			)
			(layer "F.Fab")
		)
		(fp_line
			(start 0.120396 0.2794)
			(end -0.12065 0.2794)
			(stroke
				(width 0.1)
				(type default)
			)
			(layer "F.Fab")
		)
		(fp_line
			(start 0.120396 0.3048)
			(end 0.120396 0.2794)
			(stroke
				(width 0.1)
				(type default)
			)
			(layer "F.Fab")
		)
		(fp_line
			(start 0.12065 -0.3048)
			(end 0.67945 -0.3048)
			(stroke
				(width 0.1)
				(type default)
			)
			(layer "F.Fab")
		)
		(fp_line
			(start 0.12065 -0.2794)
			(end 0.12065 -0.3048)
			(stroke
				(width 0.1)
				(type default)
			)
			(layer "F.Fab")
		)
		(fp_line
			(start 0.67945 -0.3048)
			(end 0.67945 0.3048)
			(stroke
				(width 0.1)
				(type default)
			)
			(layer "F.Fab")
		)
		(fp_line
			(start 0.67945 0.3048)
			(end 0.120396 0.3048)
			(stroke
				(width 0.1)
				(type default)
			)
			(layer "F.Fab")
		)
		(pad "1" smd circle
			(at -0.40005 0)
			(size 0 0)
			(layers "F.Cu" "F.Mask" "F.Paste")
			(net "PVCCIN_CPU0_VIN_CSNIN")
		)
		(pad "2" smd circle
			(at 0.40005 0)
			(size 0 0)
			(layers "F.Cu" "F.Mask" "F.Paste")
			(net "GND")
		)
	)
	(footprint ""
		(layer "F.Cu")
		(at 56.282844 -358.11841)
		(property "Reference" "PC725_P1_2"
			(at 0 0 0)
			(layer "F.SilkS")
			(hide yes)
			(effects
				(font
					(size 1.27 1.27)
				)
			)
		)
		(property "Value" ""
			(at 0 0 0)
			(layer "F.Fab")
			(effects
				(font
					(size 1.27 1.27)
				)
			)
		)
		(duplicate_pad_numbers_are_jumpers no)
		(fp_line
			(start -1.524 -0.762)
			(end 1.524 -0.762)
			(stroke
				(width 0.1524)
				(type default)
			)
			(layer "F.SilkS")
		)
		(fp_line
			(start -1.524 0.762)
			(end -1.524 -0.762)
			(stroke
				(width 0.1524)
				(type default)
			)
			(layer "F.SilkS")
		)
		(fp_line
			(start 1.524 -0.762)
			(end 1.524 0.762)
			(stroke
				(width 0.1524)
				(type default)
			)
			(layer "F.SilkS")
		)
		(fp_line
			(start 1.524 0.762)
			(end -1.524 0.762)
			(stroke
				(width 0.1524)
				(type default)
			)
			(layer "F.SilkS")
		)
		(fp_line
			(start -1.1049 -0.724916)
			(end -1.1049 0.724916)
			(stroke
				(width 0.1)
				(type default)
			)
			(layer "F.Fab")
		)
		(fp_line
			(start -1.1049 0.724916)
			(end 1.1049 0.724916)
			(stroke
				(width 0.1)
				(type default)
			)
			(layer "F.Fab")
		)
		(fp_line
			(start 1.1049 -0.724916)
			(end -1.1049 -0.724916)
			(stroke
				(width 0.1)
				(type default)
			)
			(layer "F.Fab")
		)
		(fp_line
			(start 1.1049 0.724916)
			(end 1.1049 -0.724916)
			(stroke
				(width 0.1)
				(type default)
			)
			(layer "F.Fab")
		)
		(pad "1" smd rect
			(at -0.889 0 180)
			(size 1.016 1.27)
			(layers "F.Cu" "F.Mask" "F.Paste")
			(net "SW_P12V_PVCCFA_EHV_FIVRA_CPU1_L")
		)
		(pad "2" smd rect
			(at 0.889 0 180)
			(size 1.016 1.27)
			(layers "F.Cu" "F.Mask" "F.Paste")
			(net "GND")
		)
	)
	(footprint ""
		(layer "F.Cu")
		(at 24.67356 -71.821548)
		(property "Reference" "U59"
			(at -1.4732 -1.768348 0)
			(unlocked yes)
			(layer "F.SilkS")
			(effects
				(font
					(size 0.7874 0.5842)
					(thickness 0.1524)
				)
				(justify left)
			)
		)
		(property "Value" ""
			(at 0 0 0)
			(layer "F.Fab")
			(effects
				(font
					(size 1.27 1.27)
				)
			)
		)
		(duplicate_pad_numbers_are_jumpers no)
		(fp_line
			(start -1.38176 -1.100074)
			(end -1.38176 1.100074)
			(stroke
				(width 0.1524)
				(type default)
			)
			(layer "F.SilkS")
		)
		(fp_line
			(start -1.38176 1.100074)
			(end 1.38176 1.100074)
			(stroke
				(width 0.1524)
				(type default)
			)
			(layer "F.SilkS")
		)
		(fp_line
			(start -0.592074 -1.100074)
			(end -1.38176 -1.100074)
			(stroke
				(width 0.1524)
				(type default)
			)
			(layer "F.SilkS")
		)
		(fp_line
			(start 0 -0.508)
			(end -0.592074 -1.100074)
			(stroke
				(width 0.1524)
				(type default)
			)
			(layer "F.SilkS")
		)
		(fp_line
			(start 0.592074 -1.100074)
			(end 0 -0.508)
			(stroke
				(width 0.1524)
				(type default)
			)
			(layer "F.SilkS")
		)
		(fp_line
			(start 1.38176 -1.100074)
			(end 0.592074 -1.100074)
			(stroke
				(width 0.1524)
				(type default)
			)
			(layer "F.SilkS")
		)
		(fp_line
			(start 1.38176 1.100074)
			(end 1.38176 -1.100074)
			(stroke
				(width 0.1524)
				(type default)
			)
			(layer "F.SilkS")
		)
		(fp_poly
			(pts
				(xy -1.60909 -0.649986) (xy -2.04978 -0.429768) (xy -2.04978 -0.870204)
			)
			(stroke
				(width 0)
				(type default)
			)
			(fill yes)
			(layer "F.SilkS")
		)
		(fp_line
			(start -0.674878 -1.100074)
			(end -0.674878 1.100074)
			(stroke
				(width 0.1)
				(type default)
			)
			(layer "F.Fab")
		)
		(fp_line
			(start -0.674878 1.100074)
			(end 0.674878 1.100074)
			(stroke
				(width 0.1)
				(type default)
			)
			(layer "F.Fab")
		)
		(fp_line
			(start 0.674878 -1.100074)
			(end -0.674878 -1.100074)
			(stroke
				(width 0.1)
				(type default)
			)
			(layer "F.Fab")
		)
		(fp_line
			(start 0.674878 1.100074)
			(end 0.674878 -1.100074)
			(stroke
				(width 0.1)
				(type default)
			)
			(layer "F.Fab")
		)
		(fp_poly
			(pts
				(xy -1.9431 -0.870204) (xy -1.50241 -0.649986) (xy -1.9431 -0.429768)
			)
			(stroke
				(width 0)
				(type default)
			)
			(fill yes)
			(layer "F.Fab")
		)
		(pad "1" smd rect
			(at -0.94996 -0.649986 270)
			(size 0.4318 0.6096)
			(layers "F.Cu" "F.Mask" "F.Paste")
			(net "OCP_V3_2_PRSNT2_R_N")
		)
		(pad "2" smd rect
			(at -0.94996 0 270)
			(size 0.4318 0.6096)
			(layers "F.Cu" "F.Mask" "F.Paste")
			(net "GND")
		)
		(pad "3" smd rect
			(at -0.94996 0.649986 270)
			(size 0.4318 0.6096)
			(layers "F.Cu" "F.Mask" "F.Paste")
			(net "OCP_V3_2_PRSNT3_R_N")
		)
		(pad "4" smd rect
			(at 0.94996 0.649986 270)
			(size 0.4318 0.6096)
			(layers "F.Cu" "F.Mask" "F.Paste")
			(net "HP_LVC3_OCP_V3_2_PRSNT2_N_R")
		)
		(pad "5" smd rect
			(at 0.94996 0 270)
			(size 0.4318 0.6096)
			(layers "F.Cu" "F.Mask" "F.Paste")
			(net "P3V3_AUX")
		)
		(pad "6" smd rect
			(at 0.94996 -0.649986 270)
			(size 0.4318 0.6096)
			(layers "F.Cu" "F.Mask" "F.Paste")
			(net "HP_LVC3_OCP_V3_2_PRSNT2_N_R")
		)
	)
	(footprint ""
		(layer "F.Cu")
		(at 380.899924 -22.29993)
		(property "Reference" "H105"
			(at -6.516624 -4.37896 0)
			(unlocked yes)
			(layer "F.SilkS")
			(effects
				(font
					(size 0.7874 0.5842)
					(thickness 0.1524)
				)
				(justify left)
			)
		)
		(property "Value" ""
			(at 0 0 0)
			(layer "F.Fab")
			(effects
				(font
					(size 1.27 1.27)
				)
			)
		)
		(duplicate_pad_numbers_are_jumpers no)
		(pad "1" thru_hole circle
			(at 0 0)
			(size 10.0076 10.0076)
			(drill 5.6134)
			(layers "*.Cu" "*.Mask")
			(remove_unused_layers no)
			(net "GND")
			(clearance -1.9431)
		)
	)
)
